(kicad_pcb
	(version 20241229)
	(generator "pcbnew")
	(generator_version "9.0")
	(general
		(thickness 1.61)
		(legacy_teardrops no)
	)
	(paper "A3")
	(title_block
		(title "RDIMM DDR5 Tester")
		(date "2026-05-21")
		(rev "2.2.0")
		(company "Antmicro")
		(comment 9 "footprints 341-343 of 796")
	)
	(layers
		(0 "F.Cu" signal)
		(4 "In1.Cu" power)
		(6 "In2.Cu" mixed)
		(8 "In3.Cu" power)
		(10 "In4.Cu" mixed)
		(12 "In5.Cu" power)
		(14 "In6.Cu" mixed)
		(16 "In7.Cu" power)
		(18 "In8.Cu" power)
		(20 "In9.Cu" mixed)
		(22 "In10.Cu" power)
		(2 "B.Cu" signal)
		(9 "F.Adhes" user "F.Adhesive")
		(11 "B.Adhes" user "B.Adhesive")
		(13 "F.Paste" user)
		(15 "B.Paste" user)
		(5 "F.SilkS" user "F.Silkscreen")
		(7 "B.SilkS" user "B.Silkscreen")
		(1 "F.Mask" user)
		(3 "B.Mask" user)
		(17 "Dwgs.User" user "User.Drawings")
		(19 "Cmts.User" user "User.Comments")
		(21 "Eco1.User" user "User.Eco1")
		(23 "Eco2.User" user "User.Eco2")
		(25 "Edge.Cuts" user)
		(27 "Margin" user)
		(31 "F.CrtYd" user "F.Courtyard")
		(29 "B.CrtYd" user "B.Courtyard")
		(35 "F.Fab" user)
		(33 "B.Fab" user)
	)
	(footprint "antmicro-footprints:USB-C_Receptacle_GCT_USB4105-GF-A"
		(layer "F.Cu")
		(at 102.825 143.765 -90)
		(property "Reference" "J3"
			(at 6.084 2.600501 0)
			(layer "F.SilkS")
			(effects
				(font
					(size 0.7 0.7)
					(thickness 0.15)
				)
				(justify left bottom)
			)
		)
		(property "Value" "USB-C_GCT_USB4105-GF-A"
			(at 0 5 90)
			(layer "F.Fab")
			(effects
				(font
					(size 0.7 0.7)
					(thickness 0.15)
				)
				(justify right bottom)
			)
		)
		(property "Datasheet" "https://gct.co/files/drawings/usb4105.pdf"
			(at 0 0 270)
			(layer "F.Fab")
			(hide yes)
			(effects
				(font
					(size 1.27 1.27)
					(thickness 0.15)
				)
			)
		)
		(property "Manufacturer" "GCT"
			(at 0 0 270)
			(unlocked yes)
			(layer "F.Fab")
			(hide yes)
			(effects
				(font
					(size 1 1)
					(thickness 0.15)
				)
			)
		)
		(property "MPN" "USB4105-GF-A"
			(at 0 0 270)
			(unlocked yes)
			(layer "F.Fab")
			(hide yes)
			(effects
				(font
					(size 1 1)
					(thickness 0.15)
				)
			)
		)
		(property "Author" "Antmicro"
			(at 0 0 270)
			(unlocked yes)
			(layer "F.Fab")
			(hide yes)
			(effects
				(font
					(size 1 1)
					(thickness 0.15)
				)
			)
		)
		(property "License" "Apache-2.0"
			(at 0 0 270)
			(unlocked yes)
			(layer "F.Fab")
			(hide yes)
			(effects
				(font
					(size 1 1)
					(thickness 0.15)
				)
			)
		)
		(sheetname "/Debug FTDI + VNA/")
		(sheetfile "debug-ftdi.kicad_sch")
		(attr smd)
		(fp_line
			(start -4.79 3.854)
			(end 4.788 3.854)
			(stroke
				(width 0.15)
				(type solid)
			)
			(layer "F.SilkS")
		)
		(fp_line
			(start 4.788 3.854)
			(end 4.788 2.575)
			(stroke
				(width 0.15)
				(type solid)
			)
			(layer "F.SilkS")
		)
		(fp_line
			(start -4.79 2.575)
			(end -4.79 3.854)
			(stroke
				(width 0.15)
				(type solid)
			)
			(layer "F.SilkS")
		)
		(fp_line
			(start -4.79 -1.395)
			(end -4.79 -0.145)
			(stroke
				(width 0.15)
				(type solid)
			)
			(layer "F.SilkS")
		)
		(fp_line
			(start 4.788 -1.395)
			(end 4.788 -0.145)
			(stroke
				(width 0.15)
				(type solid)
			)
			(layer "F.SilkS")
		)
		(fp_circle
			(center -3.8 -4.27071)
			(end -3.75 -4.22071)
			(stroke
				(width 0.15)
				(type solid)
			)
			(fill yes)
			(layer "F.SilkS")
		)
		(fp_rect
			(start -5.1 -4.4)
			(end 5.1 3.9)
			(stroke
				(width 0.05)
				(type solid)
			)
			(fill no)
			(layer "F.CrtYd")
		)
		(fp_line
			(start -4.79 3.854)
			(end -4.79 -3.676)
			(stroke
				(width 0.15)
				(type solid)
			)
			(layer "F.Fab")
		)
		(fp_line
			(start -4.702 3.854)
			(end 4.788 3.854)
			(stroke
				(width 0.15)
				(type solid)
			)
			(layer "F.Fab")
		)
		(fp_line
			(start 4.788 3.854)
			(end -4.79 3.854)
			(stroke
				(width 0.15)
				(type solid)
			)
			(layer "F.Fab")
		)
		(fp_line
			(start -4.79 -3.676)
			(end 4.788 -3.676)
			(stroke
				(width 0.15)
				(type solid)
			)
			(layer "F.Fab")
		)
		(fp_line
			(start 4.788 -3.676)
			(end 4.788 3.854)
			(stroke
				(width 0.15)
				(type solid)
			)
			(layer "F.Fab")
		)
		(fp_text user "${REFERENCE}"
			(at -4.79 6.853 270)
			(layer "F.Fab")
			(effects
				(font
					(size 0.7 0.7)
					(thickness 0.15)
				)
				(justify left bottom)
			)
		)
		(fp_text user "Author: Antmicro"
			(at -4.79 7.853 270)
			(layer "F.Fab")
			(effects
				(font
					(size 0.7 0.7)
					(thickness 0.15)
				)
				(justify left bottom)
			)
		)
		(fp_text user "PCB-EDGE"
			(at -4.79 5.853 270)
			(layer "F.Fab")
			(effects
				(font
					(size 0.7 0.7)
					(thickness 0.15)
				)
				(justify left bottom)
			)
		)
		(fp_text user "License: Apache-2.0"
			(at -4.79 8.855 270)
			(layer "F.Fab")
			(effects
				(font
					(size 0.7 0.7)
					(thickness 0.15)
				)
				(justify left bottom)
			)
		)
		(pad "" np_thru_hole circle
			(at -2.891 -2.426 270)
			(size 0.65 0.65)
			(drill 0.65)
			(layers "*.Cu" "*.Mask")
		)
		(pad "" np_thru_hole circle
			(at 2.89 -2.426 270)
			(size 0.65 0.65)
			(drill 0.65)
			(layers "*.Cu" "*.Mask")
		)
		(pad "A1" smd roundrect
			(at -3.202 -3.5 270)
			(size 0.6 1.15)
			(layers "F.Cu" "F.Mask" "F.Paste")
			(roundrect_rratio 0.25)
			(net 1 "GND")
			(pinfunction "GND")
			(pintype "power_in")
		)
		(pad "A4" smd roundrect
			(at -2.4 -3.5 270)
			(size 0.6 1.15)
			(layers "F.Cu" "F.Mask" "F.Paste")
			(roundrect_rratio 0.25)
			(net 2 "/Debug FTDI + VNA/VBUS")
			(pinfunction "VBUS")
			(pintype "passive")
		)
		(pad "A5" smd roundrect
			(at -1.25 -3.5 270)
			(size 0.3 1.15)
			(layers "F.Cu" "F.Mask" "F.Paste")
			(roundrect_rratio 0.25)
			(net 363 "/Debug FTDI + VNA/CC1")
			(pinfunction "CC_{1}")
			(pintype "bidirectional")
		)
		(pad "A6" smd roundrect
			(at -0.25 -3.5 270)
			(size 0.3 1.15)
			(layers "F.Cu" "F.Mask" "F.Paste")
			(roundrect_rratio 0.25)
			(net 364 "/Debug FTDI + VNA/DBG_USB_P")
			(pinfunction "D_{A}+")
			(pintype "bidirectional")
		)
		(pad "A7" smd roundrect
			(at 0.248 -3.5 270)
			(size 0.3 1.15)
			(layers "F.Cu" "F.Mask" "F.Paste")
			(roundrect_rratio 0.25)
			(net 365 "/Debug FTDI + VNA/DBG_USB_N")
			(pinfunction "D_{A}-")
			(pintype "bidirectional")
		)
		(pad "A8" smd roundrect
			(at 1.249 -3.5 270)
			(size 0.3 1.15)
			(layers "F.Cu" "F.Mask" "F.Paste")
			(roundrect_rratio 0.25)
			(net 243 "unconnected-(J3-SBU_{1}-PadA8)")
			(pinfunction "SBU_{1}")
			(pintype "bidirectional+no_connect")
		)
		(pad "A9" smd roundrect
			(at 2.398 -3.5 270)
			(size 0.6 1.15)
			(layers "F.Cu" "F.Mask" "F.Paste")
			(roundrect_rratio 0.25)
			(net 2 "/Debug FTDI + VNA/VBUS")
			(pinfunction "VBUS")
			(pintype "passive")
		)
		(pad "A12" smd roundrect
			(at 3.2 -3.5 270)
			(size 0.6 1.15)
			(layers "F.Cu" "F.Mask" "F.Paste")
			(roundrect_rratio 0.25)
			(net 1 "GND")
			(pinfunction "GND")
			(pintype "passive")
		)
		(pad "B1" smd roundrect
			(at 3.2 -3.5 270)
			(size 0.6 1.15)
			(layers "F.Cu" "F.Mask" "F.Paste")
			(roundrect_rratio 0.25)
			(net 1 "GND")
			(pinfunction "GND")
			(pintype "passive")
		)
		(pad "B4" smd roundrect
			(at 2.398 -3.5 270)
			(size 0.6 1.15)
			(layers "F.Cu" "F.Mask" "F.Paste")
			(roundrect_rratio 0.25)
			(net 2 "/Debug FTDI + VNA/VBUS")
			(pinfunction "VBUS")
			(pintype "passive")
		)
		(pad "B5" smd roundrect
			(at 1.749 -3.5 270)
			(size 0.3 1.15)
			(layers "F.Cu" "F.Mask" "F.Paste")
			(roundrect_rratio 0.25)
			(net 366 "/Debug FTDI + VNA/CC2")
			(pinfunction "CC_{2}")
			(pintype "bidirectional")
		)
		(pad "B6" smd roundrect
			(at 0.748 -3.5 270)
			(size 0.3 1.15)
			(layers "F.Cu" "F.Mask" "F.Paste")
			(roundrect_rratio 0.25)
			(net 364 "/Debug FTDI + VNA/DBG_USB_P")
			(pinfunction "D_{B}+")
			(pintype "bidirectional")
		)
		(pad "B7" smd roundrect
			(at -0.75 -3.5 270)
			(size 0.3 1.15)
			(layers "F.Cu" "F.Mask" "F.Paste")
			(roundrect_rratio 0.25)
			(net 365 "/Debug FTDI + VNA/DBG_USB_N")
			(pinfunction "D_{B}-")
			(pintype "bidirectional")
		)
		(pad "B8" smd roundrect
			(at -1.75 -3.5 270)
			(size 0.3 1.15)
			(layers "F.Cu" "F.Mask" "F.Paste")
			(roundrect_rratio 0.25)
			(net 245 "unconnected-(J3-SBU_{2}-PadB8)")
			(pinfunction "SBU_{2}")
			(pintype "bidirectional+no_connect")
		)
		(pad "B9" smd roundrect
			(at -2.4 -3.5 270)
			(size 0.6 1.15)
			(layers "F.Cu" "F.Mask" "F.Paste")
			(roundrect_rratio 0.25)
			(net 2 "/Debug FTDI + VNA/VBUS")
			(pinfunction "VBUS")
			(pintype "passive")
		)
		(pad "B12" smd roundrect
			(at -3.202 -3.5 270)
			(size 0.6 1.15)
			(layers "F.Cu" "F.Mask" "F.Paste")
			(roundrect_rratio 0.25)
			(net 1 "GND")
			(pinfunction "GND")
			(pintype "passive")
		)
		(pad "SH" thru_hole oval
			(at -4.321 -2.926 270)
			(size 1.05 2.1)
			(drill oval 0.6 1.7)
			(layers "*.Cu" "*.Mask")
			(remove_unused_layers no)
			(net 321 "Net-(C133-Pad1)")
			(pinfunction "SH")
			(pintype "passive")
		)
		(pad "SH" thru_hole oval
			(at -4.321 1.255 270)
			(size 1 2)
			(drill oval 0.6 1.4)
			(layers "*.Cu" "*.Mask")
			(remove_unused_layers no)
			(net 321 "Net-(C133-Pad1)")
			(pinfunction "SH")
			(pintype "passive")
		)
		(pad "SH" thru_hole oval
			(at 4.32 -2.926 270)
			(size 1.05 2.1)
			(drill oval 0.6 1.7)
			(layers "*.Cu" "*.Mask")
			(remove_unused_layers no)
			(net 321 "Net-(C133-Pad1)")
			(pinfunction "SH")
			(pintype "passive")
		)
		(pad "SH" thru_hole oval
			(at 4.32 1.255 270)
			(size 1 2)
			(drill oval 0.6 1.4)
			(layers "*.Cu" "*.Mask")
			(remove_unused_layers no)
			(net 321 "Net-(C133-Pad1)")
			(pinfunction "SH")
			(pintype "passive")
		)
	)
	(footprint "antmicro-footprints:DHVQFN-14-1EP_2.5x3mm"
		(layer "F.Cu")
		(at 137.024499 170.149 -90)
		(property "Reference" "U7"
			(at 1.9 3.4 0)
			(layer "F.SilkS")
			(effects
				(font
					(size 0.7 0.7)
					(thickness 0.15)
				)
				(justify left bottom)
			)
		)
		(property "Value" "TXU0304BQAR"
			(at 0 2.898 90)
			(layer "F.Fab")
			(effects
				(font
					(size 0.7 0.7)
					(thickness 0.15)
				)
				(justify right bottom)
			)
		)
		(property "Datasheet" "https://www.ti.com/lit/ds/symlink/txu0304.pdf?ts=1637748643258&ref_url=https%253A%252F%252Fwww.ti.com%252Fproduct%252FTXU0304"
			(at 0 0 270)
			(layer "F.Fab")
			(hide yes)
			(effects
				(font
					(size 1.27 1.27)
					(thickness 0.15)
				)
			)
		)
		(property "MPN" "TXU0304BQAR"
			(at 0 0 270)
			(unlocked yes)
			(layer "F.Fab")
			(hide yes)
			(effects
				(font
					(size 1 1)
					(thickness 0.15)
				)
			)
		)
		(property "Manufacturer" "Texas Instruments"
			(at 0 0 270)
			(unlocked yes)
			(layer "F.Fab")
			(hide yes)
			(effects
				(font
					(size 1 1)
					(thickness 0.15)
				)
			)
		)
		(property "Author" "Antmicro"
			(at 0 0 270)
			(unlocked yes)
			(layer "F.Fab")
			(hide yes)
			(effects
				(font
					(size 1 1)
					(thickness 0.15)
				)
			)
		)
		(property "License" "Apache-2.0"
			(at 0 0 270)
			(unlocked yes)
			(layer "F.Fab")
			(hide yes)
			(effects
				(font
					(size 1 1)
					(thickness 0.15)
				)
			)
		)
		(sheetname "/Debug FTDI + VNA/")
		(sheetfile "debug-ftdi.kicad_sch")
		(attr smd)
		(fp_line
			(start -1.35 1.6)
			(end -0.5 1.6)
			(stroke
				(width 0.15)
				(type solid)
			)
			(layer "F.SilkS")
		)
		(fp_line
			(start -1.35 1.6)
			(end -1.35 1.25)
			(stroke
				(width 0.15)
				(type solid)
			)
			(layer "F.SilkS")
		)
		(fp_line
			(start 0.5 1.6)
			(end 1.35 1.6)
			(stroke
				(width 0.15)
				(type solid)
			)
			(layer "F.SilkS")
		)
		(fp_line
			(start 1.35 1.6)
			(end 1.35 1.25)
			(stroke
				(width 0.15)
				(type solid)
			)
			(layer "F.SilkS")
		)
		(fp_line
			(start -1.35 -1.6)
			(end -1.35 -1.25)
			(stroke
				(width 0.15)
				(type solid)
			)
			(layer "F.SilkS")
		)
		(fp_line
			(start -1.35 -1.6)
			(end -0.5 -1.6)
			(stroke
				(width 0.15)
				(type solid)
			)
			(layer "F.SilkS")
		)
		(fp_line
			(start 1.35 -1.6)
			(end 1.35 -1.25)
			(stroke
				(width 0.15)
				(type solid)
			)
			(layer "F.SilkS")
		)
		(fp_line
			(start 1.35 -1.6)
			(end 0.5 -1.6)
			(stroke
				(width 0.15)
				(type solid)
			)
			(layer "F.SilkS")
		)
		(fp_circle
			(center -0.7 -1.85)
			(end -0.65 -1.85)
			(stroke
				(width 0.15)
				(type solid)
			)
			(fill yes)
			(layer "F.SilkS")
		)
		(fp_rect
			(start -1.8 -2)
			(end 1.8 2)
			(stroke
				(width 0.05)
				(type solid)
			)
			(fill no)
			(layer "F.CrtYd")
		)
		(fp_line
			(start -1.25 1.499)
			(end -1.25 -1.25)
			(stroke
				(width 0.15)
				(type solid)
			)
			(layer "F.Fab")
		)
		(fp_line
			(start 1.249 1.499)
			(end -1.25 1.499)
			(stroke
				(width 0.15)
				(type solid)
			)
			(layer "F.Fab")
		)
		(fp_line
			(start -1.25 -1.25)
			(end -1 -1.5)
			(stroke
				(width 0.15)
				(type solid)
			)
			(layer "F.Fab")
		)
		(fp_line
			(start -1 -1.5)
			(end 1.249 -1.5)
			(stroke
				(width 0.15)
				(type solid)
			)
			(layer "F.Fab")
		)
		(fp_line
			(start 1.249 -1.5)
			(end 1.249 1.499)
			(stroke
				(width 0.15)
				(type solid)
			)
			(layer "F.Fab")
		)
		(fp_text user "${REFERENCE}"
			(at -1.841 4.897 270)
			(layer "F.Fab")
			(effects
				(font
					(size 0.7 0.7)
					(thickness 0.15)
				)
				(justify left bottom)
			)
		)
		(fp_text user "License: Apache-2.0"
			(at -1.841 6.097 270)
			(layer "F.Fab")
			(effects
				(font
					(size 0.7 0.7)
					(thickness 0.15)
				)
				(justify left bottom)
			)
		)
		(fp_text user "Author: Antmicro"
			(at -1.841 7.296 270)
			(layer "F.Fab")
			(effects
				(font
					(size 0.7 0.7)
					(thickness 0.15)
				)
				(justify left bottom)
			)
		)
		(pad "1" smd oval
			(at -0.25 -1.5 270)
			(size 0.3 0.8)
			(layers "F.Cu" "F.Mask" "F.Paste")
			(net 6 "/Debug FTDI + VNA/FTDI_3V3")
			(pinfunction "VCCA")
			(pintype "power_in")
		)
		(pad "2" smd oval
			(at -1.25 -1)
			(size 0.3 0.8)
			(layers "F.Cu" "F.Mask" "F.Paste")
			(net 788 "/Debug FTDI + VNA/FTDI_JTAG_TMS")
			(pinfunction "A1")
			(pintype "input")
		)
		(pad "3" smd oval
			(at -1.25 -0.5)
			(size 0.3 0.8)
			(layers "F.Cu" "F.Mask" "F.Paste")
			(net 781 "/Debug FTDI + VNA/FTDI_JTAG_TCK")
			(pinfunction "A2")
			(pintype "input")
		)
		(pad "4" smd oval
			(at -1.25 0)
			(size 0.3 0.8)
			(layers "F.Cu" "F.Mask" "F.Paste")
			(net 786 "/Debug FTDI + VNA/FTDI_JTAG_TDI")
			(pinfunction "A3")
			(pintype "input")
		)
		(pad "5" smd oval
			(at -1.25 0.5)
			(size 0.3 0.8)
			(layers "F.Cu" "F.Mask" "F.Paste")
			(net 787 "/Debug FTDI + VNA/FTDI_JTAG_TDO")
			(pinfunction "A4Y")
			(pintype "output")
		)
		(pad "6" smd oval
			(at -1.25 1)
			(size 0.3 0.8)
			(layers "F.Cu" "F.Mask" "F.Paste")
			(net 414 "unconnected-(U7-NC-Pad6)")
			(pinfunction "NC")
			(pintype "no_connect")
		)
		(pad "7" smd oval
			(at -0.25 1.5 270)
			(size 0.3 0.8)
			(layers "F.Cu" "F.Mask" "F.Paste")
			(net 1 "GND")
			(pinfunction "GND")
			(pintype "passive")
		)
		(pad "8" smd oval
			(at 0.25 1.5 270)
			(size 0.3 0.8)
			(layers "F.Cu" "F.Mask" "F.Paste")
			(net 197 "FTDI_DIS")
			(pinfunction "OE")
			(pintype "tri_state")
		)
		(pad "9" smd oval
			(at 1.25 1)
			(size 0.3 0.8)
			(layers "F.Cu" "F.Mask" "F.Paste")
			(net 415 "unconnected-(U7-NC-Pad9)")
			(pinfunction "NC")
			(pintype "no_connect")
		)
		(pad "10" smd oval
			(at 1.25 0.5)
			(size 0.3 0.8)
			(layers "F.Cu" "F.Mask" "F.Paste")
			(net 300 "Net-(U7-B4)")
			(pinfunction "B4")
			(pintype "input")
		)
		(pad "11" smd oval
			(at 1.25 0)
			(size 0.3 0.8)
			(layers "F.Cu" "F.Mask" "F.Paste")
			(net 299 "Net-(U7-B3Y)")
			(pinfunction "B3Y")
			(pintype "output")
		)
		(pad "12" smd oval
			(at 1.25 -0.5)
			(size 0.3 0.8)
			(layers "F.Cu" "F.Mask" "F.Paste")
			(net 298 "Net-(U7-B2Y)")
			(pinfunction "B2Y")
			(pintype "output")
		)
		(pad "13" smd oval
			(at 1.25 -1)
			(size 0.3 0.8)
			(layers "F.Cu" "F.Mask" "F.Paste")
			(net 296 "Net-(U7-B1Y)")
			(pinfunction "B1Y")
			(pintype "output")
		)
		(pad "14" smd oval
			(at 0.25 -1.5 270)
			(size 0.3 0.8)
			(layers "F.Cu" "F.Mask" "F.Paste")
			(net 797 "+1V8")
			(pinfunction "VCCB")
			(pintype "power_in")
		)
		(pad "15" smd rect
			(at 0 0 270)
			(size 1 1.5)
			(layers "F.Cu" "F.Mask" "F.Paste")
			(net 1 "GND")
			(pinfunction "GND")
			(pintype "power_in")
		)
	)
	(footprint "antmicro-footprints:R_0402_1005Metric"
		(layer "F.Cu")
		(at 134.124499 170.164 90)
		(descr "Resistor SMD 0402")
		(tags "resistor SMD 0402")
		(property "Reference" "R51"
			(at 0.839 0.425501 90)
			(layer "F.SilkS")
			(effects
				(font
					(size 0.7 0.7)
					(thickness 0.15)
				)
				(justify left bottom)
			)
		)
		(property "Value" "R_47k_0402"
			(at -1.011843 1.772047 90)
			(layer "F.Fab")
			(effects
				(font
					(size 0.7 0.7)
					(thickness 0.15)
				)
				(justify left bottom)
			)
		)
		(property "Datasheet" "https://www.bourns.com/docs/product-datasheets/cr.pdf"
			(at 0 0 90)
			(layer "F.Fab")
			(hide yes)
			(effects
				(font
					(size 1.27 1.27)
					(thickness 0.15)
				)
			)
		)
		(property "Manufacturer" "Bourns"
			(at 0 0 90)
			(unlocked yes)
			(layer "F.Fab")
			(hide yes)
			(effects
				(font
					(size 1 1)
					(thickness 0.15)
				)
			)
		)
		(property "MPN" "CR0402-FX-4702GLF"
			(at 0 0 90)
			(unlocked yes)
			(layer "F.Fab")
			(hide yes)
			(effects
				(font
					(size 1 1)
					(thickness 0.15)
				)
			)
		)
		(property "Val" "47k"
			(at 0 0 90)
			(unlocked yes)
			(layer "F.Fab")
			(hide yes)
			(effects
				(font
					(size 1 1)
					(thickness 0.15)
				)
			)
		)
		(property "License" "Apache-2.0"
			(at 0 0 90)
			(unlocked yes)
			(layer "F.Fab")
			(hide yes)
			(effects
				(font
					(size 1 1)
					(thickness 0.15)
				)
			)
		)
		(property "Author" "Antmicro"
			(at 0 0 90)
			(unlocked yes)
			(layer "F.Fab")
			(hide yes)
			(effects
				(font
					(size 1 1)
					(thickness 0.15)
				)
			)
		)
		(property "Tolerance" "1%"
			(at 0 0 90)
			(unlocked yes)
			(layer "F.Fab")
			(hide yes)
			(effects
				(font
					(size 1 1)
					(thickness 0.15)
				)
			)
		)
		(sheetname "/Debug FTDI + VNA/")
		(sheetfile "debug-ftdi.kicad_sch")
		(attr smd)
		(fp_rect
			(start -0.925 -0.47)
			(end 0.925 0.47)
			(stroke
				(width 0.05)
				(type default)
			)
			(fill no)
			(layer "F.CrtYd")
		)
		(fp_rect
			(start -0.5 -0.25)
			(end 0.5 0.25)
			(stroke
				(width 0.15)
				(type solid)
			)
			(fill no)
			(layer "F.Fab")
		)
		(fp_text user "Author: Antmicro"
			(at -0.95 4.169 90)
			(layer "F.Fab")
			(effects
				(font
					(size 0.7 0.7)
					(thickness 0.15)
				)
				(justify left bottom)
			)
		)
		(fp_text user "${REFERENCE}"
			(at -0.95 3.168 90)
			(layer "F.Fab")
			(effects
				(font
					(size 0.7 0.7)
					(thickness 0.15)
				)
				(justify left bottom)
			)
		)
		(fp_text user "License: Apache-2.0"
			(at -0.95 5.169 90)
			(layer "F.Fab")
			(effects
				(font
					(size 0.7 0.7)
					(thickness 0.15)
				)
				(justify left bottom)
			)
		)
		(pad "1" smd roundrect
			(at -0.48 0 90)
			(size 0.59 0.64)
			(layers "F.Cu" "F.Mask" "F.Paste")
			(roundrect_rratio 0.25)
			(net 197 "FTDI_DIS")
			(pintype "passive")
		)
		(pad "2" smd roundrect
			(at 0.48 0 90)
			(size 0.59 0.64)
			(layers "F.Cu" "F.Mask" "F.Paste")
			(roundrect_rratio 0.25)
			(net 797 "+1V8")
			(pintype "passive")
		)
	)
)
